(kicad_pcb
	(version 20260206)
	(generator "pcbnew")
	(generator_version "10.0")
	(general
		(thickness 1.6)
		(legacy_teardrops no)
	)
	(paper "A4")
	(title_block
		(title "netronome-mezz — pcbd0082-001_rev01_jul9_a.brd")
		(comment 1 "Open CloudServer (Microsoft) / footprints 585-591 of 714")
	)
	(layers
		(0 "F.Cu" signal "TOP")
		(4 "In1.Cu" signal "02_GND")
		(6 "In2.Cu" signal "03_SIG")
		(8 "In3.Cu" signal "04_SIG")
		(10 "In4.Cu" signal "05_GND")
		(12 "In5.Cu" signal "06_PWR1")
		(14 "In6.Cu" signal "07_SIG")
		(16 "In7.Cu" signal "08_SIG")
		(18 "In8.Cu" signal "09_GND")
		(2 "B.Cu" signal "BOTTOM")
		(9 "F.Adhes" user "F.Adhesive")
		(11 "B.Adhes" user "B.Adhesive")
		(13 "F.Paste" user "Package Geometry/Pastemask Top")
		(15 "B.Paste" user "Package Geometry/Pastemask Bottom")
		(5 "F.SilkS" user "Ref Des/Silkscreen Top")
		(7 "B.SilkS" user "Ref Des/Silkscreen Bottom")
		(1 "F.Mask" user "Board Geometry/Soldermask Top")
		(3 "B.Mask" user "Board Geometry/Soldermask Bottom")
		(17 "Dwgs.User" user "User.Drawings")
		(19 "Cmts.User" user "User.Comments")
		(21 "Eco1.User" user "User.Eco1")
		(23 "Eco2.User" user "User.Eco2")
		(25 "Edge.Cuts" user "Board Geometry/Outline")
		(27 "Margin" user)
		(31 "F.CrtYd" user "Package Geometry/Place Bound Top")
		(29 "B.CrtYd" user "Package Geometry/Place Bound Bottom")
		(35 "F.Fab" user "Ref Des/Assembly Top")
		(33 "B.Fab" user "Ref Des/Assembly Bottom")
		(45 "User.4" user "COMPVAL_TYPE_BOTTOM")
	)
	(footprint ""
		(layer "B.Cu")
		(at 42.237152 21.542121 180)
		(property "Reference" "R409"
			(at 0 0 0)
			(layer "B.SilkS")
			(hide yes)
			(effects
				(font
					(size 1.27 1.27)
				)
				(justify mirror)
			)
		)
		(property "Value" ""
			(at 0 0 0)
			(layer "B.Fab")
			(effects
				(font
					(size 1.27 1.27)
				)
				(justify mirror)
			)
		)
		(duplicate_pad_numbers_are_jumpers no)
		(fp_circle
			(center 0 0)
			(end -0.104648 0)
			(stroke
				(width 0.1016)
				(type default)
			)
			(fill no)
			(layer "B.SilkS")
		)
		(fp_poly
			(pts
				(xy 0.381 -0.889) (xy 0.381 0.889) (xy -0.381 0.889) (xy -0.381 -0.889)
			)
			(stroke
				(width 0)
				(type default)
			)
			(fill no)
			(layer "B.CrtYd")
		)
		(fp_line
			(start 0.508 1.016)
			(end 0.508 -1.016)
			(stroke
				(width 0.0254)
				(type default)
			)
			(layer "B.Fab")
		)
		(fp_line
			(start 0.508 -1.016)
			(end 0.254 -1.016)
			(stroke
				(width 0.0254)
				(type default)
			)
			(layer "B.Fab")
		)
		(fp_line
			(start 0.254 -1.016)
			(end -0.508 -1.016)
			(stroke
				(width 0.0254)
				(type default)
			)
			(layer "B.Fab")
		)
		(fp_line
			(start -0.508 1.016)
			(end 0.508 1.016)
			(stroke
				(width 0.0254)
				(type default)
			)
			(layer "B.Fab")
		)
		(fp_line
			(start -0.508 -1.016)
			(end -0.508 1.016)
			(stroke
				(width 0.0254)
				(type default)
			)
			(layer "B.Fab")
		)
		(pad "1" smd custom
			(at 0 -0.500126)
			(size 0.127 0.127)
			(layers "B.Cu" "B.Mask" "B.Paste")
			(net "_NFP_PCIE0_RESET_OUT_L")
			(options
				(clearance outline)
				(anchor circle)
			)
			(primitives
				(gr_poly
					(pts
						(xy -0.1778 0.254) (xy 0.1778 0.254) (xy 0.254 0.1778) (xy 0.254 -0.1778) (xy 0.1778 -0.254) (xy -0.1778 -0.254)
						(xy -0.254 -0.1778) (xy -0.254 0.1778)
					)
					(width 0)
					(fill yes)
				)
			)
		)
		(pad "2" smd custom
			(at 0 0.500126)
			(size 0.127 0.127)
			(layers "B.Cu" "B.Mask" "B.Paste")
			(net "NFP_PCIE0_RESET_OUT_L")
			(options
				(clearance outline)
				(anchor circle)
			)
			(primitives
				(gr_poly
					(pts
						(xy -0.1778 0.254) (xy 0.1778 0.254) (xy 0.254 0.1778) (xy 0.254 -0.1778) (xy 0.1778 -0.254) (xy -0.1778 -0.254)
						(xy -0.254 -0.1778) (xy -0.254 0.1778)
					)
					(width 0)
					(fill yes)
				)
			)
		)
	)
	(footprint ""
		(layer "B.Cu")
		(at 43.737022 22.041993 90)
		(property "Reference" "C27"
			(at -0.463677 2.363978 0)
			(unlocked yes)
			(layer "B.SilkS")
			(effects
				(font
					(size 0.7874 0.5842)
					(thickness 0.127)
				)
				(justify mirror)
			)
		)
		(property "Value" ""
			(at 0 0 90)
			(layer "B.Fab")
			(effects
				(font
					(size 1.27 1.27)
				)
				(justify mirror)
			)
		)
		(duplicate_pad_numbers_are_jumpers no)
		(fp_circle
			(center 0 0)
			(end 0 0.104648)
			(stroke
				(width 0.1016)
				(type default)
			)
			(fill no)
			(layer "B.SilkS")
		)
		(fp_poly
			(pts
				(xy 0.381 -0.889) (xy 0.381 0.889) (xy -0.381 0.889) (xy -0.381 -0.889)
			)
			(stroke
				(width 0)
				(type default)
			)
			(fill no)
			(layer "B.CrtYd")
		)
		(fp_line
			(start 0.508 -1.016)
			(end 0.254 -1.016)
			(stroke
				(width 0.0254)
				(type default)
			)
			(layer "B.Fab")
		)
		(fp_line
			(start 0.254 -1.016)
			(end -0.508 -1.016)
			(stroke
				(width 0.0254)
				(type default)
			)
			(layer "B.Fab")
		)
		(fp_line
			(start -0.508 -1.016)
			(end -0.508 1.016)
			(stroke
				(width 0.0254)
				(type default)
			)
			(layer "B.Fab")
		)
		(fp_line
			(start 0.508 1.016)
			(end 0.508 -1.016)
			(stroke
				(width 0.0254)
				(type default)
			)
			(layer "B.Fab")
		)
		(fp_line
			(start -0.508 1.016)
			(end 0.508 1.016)
			(stroke
				(width 0.0254)
				(type default)
			)
			(layer "B.Fab")
		)
		(pad "1" smd custom
			(at 0 -0.500126 270)
			(size 0.127 0.127)
			(layers "B.Cu" "B.Mask" "B.Paste")
			(net "VDDA_PLL")
			(options
				(clearance outline)
				(anchor circle)
			)
			(primitives
				(gr_poly
					(pts
						(xy -0.1778 0.254) (xy 0.1778 0.254) (xy 0.254 0.1778) (xy 0.254 -0.1778) (xy 0.1778 -0.254) (xy -0.1778 -0.254)
						(xy -0.254 -0.1778) (xy -0.254 0.1778)
					)
					(width 0)
					(fill yes)
				)
			)
		)
		(pad "2" smd custom
			(at 0 0.500126 270)
			(size 0.127 0.127)
			(layers "B.Cu" "B.Mask" "B.Paste")
			(net "GND")
			(options
				(clearance outline)
				(anchor circle)
			)
			(primitives
				(gr_poly
					(pts
						(xy -0.1778 0.254) (xy 0.1778 0.254) (xy 0.254 0.1778) (xy 0.254 -0.1778) (xy 0.1778 -0.254) (xy -0.1778 -0.254)
						(xy -0.254 -0.1778) (xy -0.254 0.1778)
					)
					(width 0)
					(fill yes)
				)
			)
		)
	)
	(footprint ""
		(layer "B.Cu")
		(at 23.749 27.94 -90)
		(property "Reference" "R200"
			(at 1.04267 -1.016 0)
			(unlocked yes)
			(layer "B.SilkS")
			(effects
				(font
					(size 0.7874 0.5842)
					(thickness 0.127)
				)
				(justify left mirror)
			)
		)
		(property "Value" "39.0"
			(at 0.148158 1.3462 180)
			(unlocked yes)
			(layer "B.Fab")
			(hide yes)
			(effects
				(font
					(size 1.27 0.9652)
					(thickness 0.000001)
				)
				(justify left mirror)
			)
		)
		(property "Device Type" "REST0108"
			(at 0.148158 1.3462 180)
			(unlocked yes)
			(layer "B.Fab")
			(hide yes)
			(effects
				(font
					(size 1.27 0.9652)
					(thickness 0.000001)
				)
				(justify left mirror)
			)
		)
		(duplicate_pad_numbers_are_jumpers no)
		(fp_poly
			(pts
				(xy -0.635 1.0668) (xy -0.635 -1.0668) (xy 0.635 -1.0668) (xy 0.635 1.0668)
			)
			(stroke
				(width 0)
				(type default)
			)
			(fill no)
			(layer "B.CrtYd")
		)
		(fp_line
			(start -0.254 0.508)
			(end 0.254 0.508)
			(stroke
				(width 0.0254)
				(type default)
			)
			(layer "B.Fab")
		)
		(fp_line
			(start 0.254 0.508)
			(end 0.254 -0.508)
			(stroke
				(width 0.0254)
				(type default)
			)
			(layer "B.Fab")
		)
		(fp_line
			(start -0.254 -0.508)
			(end -0.254 0.508)
			(stroke
				(width 0.0254)
				(type default)
			)
			(layer "B.Fab")
		)
		(fp_line
			(start 0.254 -0.508)
			(end -0.254 -0.508)
			(stroke
				(width 0.0254)
				(type default)
			)
			(layer "B.Fab")
		)
		(pad "1" smd rect
			(at 0 -0.4191 90)
			(size 0.508 0.5334)
			(layers "B.Cu" "B.Mask" "B.Paste")
			(net "_NFP_UART_SR_TX")
		)
		(pad "2" smd rect
			(at 0 0.4191 90)
			(size 0.508 0.5334)
			(layers "B.Cu" "B.Mask" "B.Paste")
			(net "NFP_UART_SR_TX")
		)
		(zone
			(layer "B.Cu")
			(hatch none 0.5)
			(connect_pads
				(clearance 0)
			)
			(min_thickness 0.25)
			(keepout
				(tracks not_allowed)
				(vias allowed)
				(pads allowed)
				(copperpour not_allowed)
				(footprints allowed)
			)
			(placement
				(enabled no)
				(sheetname "")
			)
			(fill
				(thermal_gap 0.5)
				(thermal_bridge_width 0.5)
				(island_removal_mode 0)
			)
			(polygon
				(pts
					(xy 23.7744 27.9146) (xy 23.7236 27.9146) (xy 23.7236 27.9654) (xy 23.7744 27.9654)
				)
			)
		)
	)
	(footprint ""
		(layer "B.Cu")
		(at 41.783 35.306)
		(property "Reference" "R169"
			(at 0 0 0)
			(layer "B.SilkS")
			(hide yes)
			(effects
				(font
					(size 1.27 1.27)
				)
				(justify mirror)
			)
		)
		(property "Value" "0"
			(at 0.148158 1.3462 270)
			(unlocked yes)
			(layer "B.Fab")
			(hide yes)
			(effects
				(font
					(size 1.27 0.9652)
					(thickness 0.000001)
				)
				(justify left mirror)
			)
		)
		(property "Device Type" "REST1111"
			(at 0.148158 1.3462 270)
			(unlocked yes)
			(layer "B.Fab")
			(hide yes)
			(effects
				(font
					(size 1.27 0.9652)
					(thickness 0.000001)
				)
				(justify left mirror)
			)
		)
		(duplicate_pad_numbers_are_jumpers no)
		(fp_poly
			(pts
				(xy -0.635 1.0668) (xy -0.635 -1.0668) (xy 0.635 -1.0668) (xy 0.635 1.0668)
			)
			(stroke
				(width 0)
				(type default)
			)
			(fill no)
			(layer "B.CrtYd")
		)
		(fp_line
			(start -0.254 -0.508)
			(end -0.254 0.508)
			(stroke
				(width 0.0254)
				(type default)
			)
			(layer "B.Fab")
		)
		(fp_line
			(start -0.254 0.508)
			(end 0.254 0.508)
			(stroke
				(width 0.0254)
				(type default)
			)
			(layer "B.Fab")
		)
		(fp_line
			(start 0.254 -0.508)
			(end -0.254 -0.508)
			(stroke
				(width 0.0254)
				(type default)
			)
			(layer "B.Fab")
		)
		(fp_line
			(start 0.254 0.508)
			(end 0.254 -0.508)
			(stroke
				(width 0.0254)
				(type default)
			)
			(layer "B.Fab")
		)
		(pad "1" smd rect
			(at 0 -0.4191 180)
			(size 0.508 0.5334)
			(layers "B.Cu" "B.Mask" "B.Paste")
			(net "VR_ODN_L")
		)
		(pad "2" smd rect
			(at 0 0.4191 180)
			(size 0.508 0.5334)
			(layers "B.Cu" "B.Mask" "B.Paste")
			(net "10N2235")
		)
		(zone
			(layer "B.Cu")
			(hatch none 0.5)
			(connect_pads
				(clearance 0)
			)
			(min_thickness 0.25)
			(keepout
				(tracks not_allowed)
				(vias allowed)
				(pads allowed)
				(copperpour not_allowed)
				(footprints allowed)
			)
			(placement
				(enabled no)
				(sheetname "")
			)
			(fill
				(thermal_gap 0.5)
				(thermal_bridge_width 0.5)
				(island_removal_mode 0)
			)
			(polygon
				(pts
					(xy 41.7576 35.2806) (xy 41.7576 35.3314) (xy 41.8084 35.3314) (xy 41.8084 35.2806)
				)
			)
		)
	)
	(footprint ""
		(layer "B.Cu")
		(at 46.1899 35.6362 180)
		(property "Reference" "C203"
			(at 0 0 0)
			(layer "B.SilkS")
			(hide yes)
			(effects
				(font
					(size 1.27 1.27)
				)
				(justify mirror)
			)
		)
		(property "Value" "1UF"
			(at 0.091846 0.2921 90)
			(unlocked yes)
			(layer "B.Fab")
			(hide yes)
			(effects
				(font
					(size 0.7874 0.5842)
					(thickness 0.2032)
				)
				(justify left mirror)
			)
		)
		(property "Device Type" "CAPC0028"
			(at 0.091846 0.2921 90)
			(unlocked yes)
			(layer "B.Fab")
			(hide yes)
			(effects
				(font
					(size 0.7874 0.5842)
					(thickness 0.2032)
				)
				(justify left mirror)
			)
		)
		(duplicate_pad_numbers_are_jumpers no)
		(fp_poly
			(pts
				(xy -0.635 1.0668) (xy -0.635 -1.0668) (xy 0.635 -1.0668) (xy 0.635 1.0668)
			)
			(stroke
				(width 0)
				(type default)
			)
			(fill no)
			(layer "B.CrtYd")
		)
		(fp_line
			(start 0.254 0.508)
			(end 0.254 -0.508)
			(stroke
				(width 0.0254)
				(type default)
			)
			(layer "B.Fab")
		)
		(fp_line
			(start 0.254 -0.508)
			(end -0.254 -0.508)
			(stroke
				(width 0.0254)
				(type default)
			)
			(layer "B.Fab")
		)
		(fp_line
			(start -0.254 0.508)
			(end 0.254 0.508)
			(stroke
				(width 0.0254)
				(type default)
			)
			(layer "B.Fab")
		)
		(fp_line
			(start -0.254 -0.508)
			(end -0.254 0.508)
			(stroke
				(width 0.0254)
				(type default)
			)
			(layer "B.Fab")
		)
		(pad "1" smd rect
			(at 0 -0.4191)
			(size 0.508 0.5334)
			(layers "B.Cu" "B.Mask" "B.Paste")
			(net "VDD_5.0V")
		)
		(pad "2" smd rect
			(at 0 0.4191)
			(size 0.508 0.5334)
			(layers "B.Cu" "B.Mask" "B.Paste")
			(net "GND")
		)
		(zone
			(layer "B.Cu")
			(hatch none 0.5)
			(connect_pads
				(clearance 0)
			)
			(min_thickness 0.25)
			(keepout
				(tracks not_allowed)
				(vias allowed)
				(pads allowed)
				(copperpour not_allowed)
				(footprints allowed)
			)
			(placement
				(enabled no)
				(sheetname "")
			)
			(fill
				(thermal_gap 0.5)
				(thermal_bridge_width 0.5)
				(island_removal_mode 0)
			)
			(polygon
				(pts
					(xy 46.2153 35.6616) (xy 46.2153 35.6108) (xy 46.1645 35.6108) (xy 46.1645 35.6616)
				)
			)
		)
	)
	(footprint ""
		(layer "B.Cu")
		(at 35.306 29.083 90)
		(property "Reference" "C121"
			(at -0.78867 1.397 0)
			(unlocked yes)
			(layer "B.SilkS")
			(effects
				(font
					(size 0.7874 0.5842)
					(thickness 0.127)
				)
				(justify left mirror)
			)
		)
		(property "Value" "0.1UF"
			(at 0.091846 0.2921 0)
			(unlocked yes)
			(layer "B.Fab")
			(hide yes)
			(effects
				(font
					(size 0.7874 0.5842)
					(thickness 0.2032)
				)
				(justify left mirror)
			)
		)
		(property "Device Type" "CAPC0073"
			(at 0.091846 0.2921 0)
			(unlocked yes)
			(layer "B.Fab")
			(hide yes)
			(effects
				(font
					(size 0.7874 0.5842)
					(thickness 0.2032)
				)
				(justify left mirror)
			)
		)
		(duplicate_pad_numbers_are_jumpers no)
		(fp_poly
			(pts
				(xy -0.635 1.0668) (xy -0.635 -1.0668) (xy 0.635 -1.0668) (xy 0.635 1.0668)
			)
			(stroke
				(width 0)
				(type default)
			)
			(fill no)
			(layer "B.CrtYd")
		)
		(fp_line
			(start 0.254 -0.508)
			(end -0.254 -0.508)
			(stroke
				(width 0.0254)
				(type default)
			)
			(layer "B.Fab")
		)
		(fp_line
			(start -0.254 -0.508)
			(end -0.254 0.508)
			(stroke
				(width 0.0254)
				(type default)
			)
			(layer "B.Fab")
		)
		(fp_line
			(start 0.254 0.508)
			(end 0.254 -0.508)
			(stroke
				(width 0.0254)
				(type default)
			)
			(layer "B.Fab")
		)
		(fp_line
			(start -0.254 0.508)
			(end 0.254 0.508)
			(stroke
				(width 0.0254)
				(type default)
			)
			(layer "B.Fab")
		)
		(pad "1" smd rect
			(at 0 -0.4191 270)
			(size 0.508 0.5334)
			(layers "B.Cu" "B.Mask" "B.Paste")
			(net "EXT_3.3V")
		)
		(pad "2" smd rect
			(at 0 0.4191 270)
			(size 0.508 0.5334)
			(layers "B.Cu" "B.Mask" "B.Paste")
			(net "GND")
		)
		(zone
			(layer "B.Cu")
			(hatch none 0.5)
			(connect_pads
				(clearance 0)
			)
			(min_thickness 0.25)
			(keepout
				(tracks not_allowed)
				(vias allowed)
				(pads allowed)
				(copperpour not_allowed)
				(footprints allowed)
			)
			(placement
				(enabled no)
				(sheetname "")
			)
			(fill
				(thermal_gap 0.5)
				(thermal_bridge_width 0.5)
				(island_removal_mode 0)
			)
			(polygon
				(pts
					(xy 35.2806 29.1084) (xy 35.3314 29.1084) (xy 35.3314 29.0576) (xy 35.2806 29.0576)
				)
			)
		)
	)
	(footprint ""
		(layer "B.Cu")
		(at 83.450989 30.612994)
		(property "Reference" "V3_A-A06"
			(at 0 0 0)
			(layer "B.SilkS")
			(hide yes)
			(effects
				(font
					(size 1.27 1.27)
				)
				(justify mirror)
			)
		)
		(property "Value" ""
			(at 0 0 0)
			(layer "B.Fab")
			(effects
				(font
					(size 1.27 1.27)
				)
				(justify mirror)
			)
		)
		(duplicate_pad_numbers_are_jumpers no)
		(pad "1" thru_hole circle
			(at 0 0 180)
			(size 0.4572 0.4572)
			(drill 0.20574)
			(layers "*.Cu" "*.Mask")
			(remove_unused_layers no)
			(net "DDR0_32A_A6")
			(clearance 0.1143)
			(thermal_gap 0.1143)
		)
	)
)
